(kicad_pcb
	(version 20241229)
	(generator "pcbnew")
	(generator_version "9.0")
	(general
		(thickness 1.294)
		(legacy_teardrops no)
	)
	(paper "A3")
	(title_block
		(title "Kintex 410T devboard")
		(date "2024-04-03")
		(rev "1.1.2")
		(comment 9 "footprints 13-13 of 975")
	)
	(layers
		(0 "F.Cu" mixed)
		(4 "In1.Cu" power)
		(6 "In2.Cu" power)
		(8 "In3.Cu" mixed)
		(10 "In4.Cu" power)
		(12 "In5.Cu" mixed)
		(14 "In6.Cu" power)
		(16 "In7.Cu" mixed)
		(18 "In8.Cu" power)
		(2 "B.Cu" mixed)
		(9 "F.Adhes" user "F.Adhesive")
		(11 "B.Adhes" user "B.Adhesive")
		(13 "F.Paste" user)
		(15 "B.Paste" user)
		(5 "F.SilkS" user "F.Silkscreen")
		(7 "B.SilkS" user "B.Silkscreen")
		(1 "F.Mask" user)
		(3 "B.Mask" user)
		(17 "Dwgs.User" user "User.Drawings")
		(19 "Cmts.User" user "User.Comments")
		(21 "Eco1.User" user "User.Eco1")
		(23 "Eco2.User" user "User.Eco2")
		(25 "Edge.Cuts" user)
		(27 "Margin" user)
		(31 "F.CrtYd" user "F.Courtyard")
		(29 "B.CrtYd" user "B.Courtyard")
		(35 "F.Fab" user)
		(33 "B.Fab" user)
	)
	(footprint "antmicro-footprints:Conn_Socket_Samtec_ERF5_2x20_ERF5-020-05.0-L-DV-K-TR"
		(locked yes)
		(layer "F.Cu")
		(at 249.9 148.1)
		(property "Reference" "J22"
			(at 5.11 3.59 0)
			(layer "F.SilkS")
			(effects
				(font
					(size 0.7 0.7)
					(thickness 0.15)
				)
				(justify left bottom)
			)
		)
		(property "Value" "Socket_Samtec_ERF5_2x20_ERF5-020-05.0-L-DV-K-TR"
			(at 0 3.9 0)
			(layer "F.Fab")
			(effects
				(font
					(size 0.7 0.7)
					(thickness 0.15)
				)
				(justify left bottom)
			)
		)
		(property "Description" "Board to Board & Mezzanine Connectors 0.50 mm Edge Rate Rugged High Speed Socket"
			(at 0 0 0)
			(layer "F.Fab")
			(hide yes)
			(effects
				(font
					(size 1.27 1.27)
					(thickness 0.15)
				)
			)
		)
		(property "Author" "Antmicro"
			(at 0 0 0)
			(layer "F.Fab")
			(hide yes)
			(effects
				(font
					(size 1 1)
					(thickness 0.15)
				)
			)
		)
		(property "License" "Apache-2.0"
			(at 0 0 0)
			(layer "F.Fab")
			(hide yes)
			(effects
				(font
					(size 1 1)
					(thickness 0.15)
				)
			)
		)
		(property "MPN" "ERF5-020-05.0-L-DV-K-TR"
			(at 0 0 0)
			(layer "F.Fab")
			(hide yes)
			(effects
				(font
					(size 1 1)
					(thickness 0.15)
				)
			)
		)
		(property "Manufacturer" "Samtec"
			(at 0 0 0)
			(layer "F.Fab")
			(hide yes)
			(effects
				(font
					(size 1 1)
					(thickness 0.15)
				)
			)
		)
		(property "Pitch" "0.5 mm"
			(at 0 0 0)
			(layer "F.Fab")
			(hide yes)
			(effects
				(font
					(size 1 1)
					(thickness 0.15)
				)
			)
		)
		(sheetname "Supervisior MCU")
		(sheetfile "supervisor-mcu.kicad_sch")
		(attr smd)
		(fp_line
			(start -8.4 -2.475)
			(end -5.349 -2.475)
			(stroke
				(width 0.15)
				(type solid)
			)
			(layer "F.SilkS")
		)
		(fp_line
			(start -8.4 2.476)
			(end -8.4 -2.475)
			(stroke
				(width 0.15)
				(type solid)
			)
			(layer "F.SilkS")
		)
		(fp_line
			(start -5.349 2.476)
			(end -8.4 2.476)
			(stroke
				(width 0.15)
				(type solid)
			)
			(layer "F.SilkS")
		)
		(fp_line
			(start 5.351 -2.475)
			(end 8.401 -2.475)
			(stroke
				(width 0.15)
				(type solid)
			)
			(layer "F.SilkS")
		)
		(fp_line
			(start 8.401 -2.475)
			(end 8.401 2.476)
			(stroke
				(width 0.15)
				(type solid)
			)
			(layer "F.SilkS")
		)
		(fp_line
			(start 8.401 2.476)
			(end 5.351 2.476)
			(stroke
				(width 0.15)
				(type solid)
			)
			(layer "F.SilkS")
		)
		(fp_circle
			(center -5.2 2.9)
			(end -5.25 2.9)
			(stroke
				(width 0.15)
				(type solid)
			)
			(fill no)
			(layer "F.SilkS")
		)
		(fp_poly
			(pts
				(xy -4.623 -1.225) (xy -4.876 -1.225) (xy -4.876 -2.725) (xy -4.623 -2.725)
			)
			(stroke
				(width 0.01)
				(type solid)
			)
			(fill yes)
			(layer "F.Paste")
		)
		(fp_poly
			(pts
				(xy -4.623 2.726) (xy -4.876 2.726) (xy -4.876 1.226) (xy -4.623 1.226)
			)
			(stroke
				(width 0.01)
				(type solid)
			)
			(fill yes)
			(layer "F.Paste")
		)
		(fp_poly
			(pts
				(xy -4.123 -1.225) (xy -4.376 -1.225) (xy -4.376 -2.725) (xy -4.123 -2.725)
			)
			(stroke
				(width 0.01)
				(type solid)
			)
			(fill yes)
			(layer "F.Paste")
		)
		(fp_poly
			(pts
				(xy -4.123 2.726) (xy -4.376 2.726) (xy -4.376 1.226) (xy -4.123 1.226)
			)
			(stroke
				(width 0.01)
				(type solid)
			)
			(fill yes)
			(layer "F.Paste")
		)
		(fp_poly
			(pts
				(xy -3.623 -1.225) (xy -3.875 -1.225) (xy -3.875 -2.725) (xy -3.623 -2.725)
			)
			(stroke
				(width 0.01)
				(type solid)
			)
			(fill yes)
			(layer "F.Paste")
		)
		(fp_poly
			(pts
				(xy -3.623 2.726) (xy -3.875 2.726) (xy -3.875 1.226) (xy -3.623 1.226)
			)
			(stroke
				(width 0.01)
				(type solid)
			)
			(fill yes)
			(layer "F.Paste")
		)
		(fp_poly
			(pts
				(xy -3.123 -1.225) (xy -3.375 -1.225) (xy -3.375 -2.725) (xy -3.123 -2.725)
			)
			(stroke
				(width 0.01)
				(type solid)
			)
			(fill yes)
			(layer "F.Paste")
		)
		(fp_poly
			(pts
				(xy -3.123 2.726) (xy -3.375 2.726) (xy -3.375 1.226) (xy -3.123 1.226)
			)
			(stroke
				(width 0.01)
				(type solid)
			)
			(fill yes)
			(layer "F.Paste")
		)
		(fp_poly
			(pts
				(xy -2.623 -1.225) (xy -2.875 -1.225) (xy -2.875 -2.725) (xy -2.623 -2.725)
			)
			(stroke
				(width 0.01)
				(type solid)
			)
			(fill yes)
			(layer "F.Paste")
		)
		(fp_poly
			(pts
				(xy -2.623 2.726) (xy -2.875 2.726) (xy -2.875 1.226) (xy -2.623 1.226)
			)
			(stroke
				(width 0.01)
				(type solid)
			)
			(fill yes)
			(layer "F.Paste")
		)
		(fp_poly
			(pts
				(xy -2.123 -1.225) (xy -2.375 -1.225) (xy -2.375 -2.725) (xy -2.123 -2.725)
			)
			(stroke
				(width 0.01)
				(type solid)
			)
			(fill yes)
			(layer "F.Paste")
		)
		(fp_poly
			(pts
				(xy -2.123 2.726) (xy -2.375 2.726) (xy -2.375 1.226) (xy -2.123 1.226)
			)
			(stroke
				(width 0.01)
				(type solid)
			)
			(fill yes)
			(layer "F.Paste")
		)
		(fp_poly
			(pts
				(xy -1.622 -1.225) (xy -1.876 -1.225) (xy -1.876 -2.725) (xy -1.622 -2.725)
			)
			(stroke
				(width 0.01)
				(type solid)
			)
			(fill yes)
			(layer "F.Paste")
		)
		(fp_poly
			(pts
				(xy -1.622 2.726) (xy -1.876 2.726) (xy -1.876 1.226) (xy -1.622 1.226)
			)
			(stroke
				(width 0.01)
				(type solid)
			)
			(fill yes)
			(layer "F.Paste")
		)
		(fp_poly
			(pts
				(xy -1.122 -1.225) (xy -1.376 -1.225) (xy -1.376 -2.725) (xy -1.122 -2.725)
			)
			(stroke
				(width 0.01)
				(type solid)
			)
			(fill yes)
			(layer "F.Paste")
		)
		(fp_poly
			(pts
				(xy -1.122 2.726) (xy -1.376 2.726) (xy -1.376 1.226) (xy -1.122 1.226)
			)
			(stroke
				(width 0.01)
				(type solid)
			)
			(fill yes)
			(layer "F.Paste")
		)
		(fp_poly
			(pts
				(xy -0.621 -1.225) (xy -0.875 -1.225) (xy -0.875 -2.725) (xy -0.621 -2.725)
			)
			(stroke
				(width 0.01)
				(type solid)
			)
			(fill yes)
			(layer "F.Paste")
		)
		(fp_poly
			(pts
				(xy -0.621 2.726) (xy -0.875 2.726) (xy -0.875 1.226) (xy -0.621 1.226)
			)
			(stroke
				(width 0.01)
				(type solid)
			)
			(fill yes)
			(layer "F.Paste")
		)
		(fp_poly
			(pts
				(xy -0.121 -1.225) (xy -0.375 -1.225) (xy -0.375 -2.725) (xy -0.121 -2.725)
			)
			(stroke
				(width 0.01)
				(type solid)
			)
			(fill yes)
			(layer "F.Paste")
		)
		(fp_poly
			(pts
				(xy -0.121 2.726) (xy -0.375 2.726) (xy -0.375 1.226) (xy -0.121 1.226)
			)
			(stroke
				(width 0.01)
				(type solid)
			)
			(fill yes)
			(layer "F.Paste")
		)
		(fp_poly
			(pts
				(xy 0.377 -1.225) (xy 0.123 -1.225) (xy 0.123 -2.725) (xy 0.377 -2.725)
			)
			(stroke
				(width 0.01)
				(type solid)
			)
			(fill yes)
			(layer "F.Paste")
		)
		(fp_poly
			(pts
				(xy 0.377 2.726) (xy 0.123 2.726) (xy 0.123 1.226) (xy 0.377 1.226)
			)
			(stroke
				(width 0.01)
				(type solid)
			)
			(fill yes)
			(layer "F.Paste")
		)
		(fp_poly
			(pts
				(xy 0.877 -1.225) (xy 0.623 -1.225) (xy 0.623 -2.725) (xy 0.877 -2.725)
			)
			(stroke
				(width 0.01)
				(type solid)
			)
			(fill yes)
			(layer "F.Paste")
		)
		(fp_poly
			(pts
				(xy 0.877 2.726) (xy 0.623 2.726) (xy 0.623 1.226) (xy 0.877 1.226)
			)
			(stroke
				(width 0.01)
				(type solid)
			)
			(fill yes)
			(layer "F.Paste")
		)
		(fp_poly
			(pts
				(xy 1.377 -1.225) (xy 1.123 -1.225) (xy 1.123 -2.725) (xy 1.377 -2.725)
			)
			(stroke
				(width 0.01)
				(type solid)
			)
			(fill yes)
			(layer "F.Paste")
		)
		(fp_poly
			(pts
				(xy 1.377 2.726) (xy 1.123 2.726) (xy 1.123 1.226) (xy 1.377 1.226)
			)
			(stroke
				(width 0.01)
				(type solid)
			)
			(fill yes)
			(layer "F.Paste")
		)
		(fp_poly
			(pts
				(xy 1.877 -1.225) (xy 1.623 -1.225) (xy 1.623 -2.725) (xy 1.877 -2.725)
			)
			(stroke
				(width 0.01)
				(type solid)
			)
			(fill yes)
			(layer "F.Paste")
		)
		(fp_poly
			(pts
				(xy 1.877 2.726) (xy 1.623 2.726) (xy 1.623 1.226) (xy 1.877 1.226)
			)
			(stroke
				(width 0.01)
				(type solid)
			)
			(fill yes)
			(layer "F.Paste")
		)
		(fp_poly
			(pts
				(xy 2.378 -1.225) (xy 2.125 -1.225) (xy 2.125 -2.725) (xy 2.378 -2.725)
			)
			(stroke
				(width 0.01)
				(type solid)
			)
			(fill yes)
			(layer "F.Paste")
		)
		(fp_poly
			(pts
				(xy 2.378 2.726) (xy 2.125 2.726) (xy 2.125 1.226) (xy 2.378 1.226)
			)
			(stroke
				(width 0.01)
				(type solid)
			)
			(fill yes)
			(layer "F.Paste")
		)
		(fp_poly
			(pts
				(xy 2.878 -1.225) (xy 2.625 -1.225) (xy 2.625 -2.725) (xy 2.878 -2.725)
			)
			(stroke
				(width 0.01)
				(type solid)
			)
			(fill yes)
			(layer "F.Paste")
		)
		(fp_poly
			(pts
				(xy 2.878 2.726) (xy 2.625 2.726) (xy 2.625 1.226) (xy 2.878 1.226)
			)
			(stroke
				(width 0.01)
				(type solid)
			)
			(fill yes)
			(layer "F.Paste")
		)
		(fp_poly
			(pts
				(xy 3.378 -1.225) (xy 3.125 -1.225) (xy 3.125 -2.725) (xy 3.378 -2.725)
			)
			(stroke
				(width 0.01)
				(type solid)
			)
			(fill yes)
			(layer "F.Paste")
		)
		(fp_poly
			(pts
				(xy 3.378 2.726) (xy 3.125 2.726) (xy 3.125 1.226) (xy 3.378 1.226)
			)
			(stroke
				(width 0.01)
				(type solid)
			)
			(fill yes)
			(layer "F.Paste")
		)
		(fp_poly
			(pts
				(xy 3.878 -1.225) (xy 3.625 -1.225) (xy 3.625 -2.725) (xy 3.878 -2.725)
			)
			(stroke
				(width 0.01)
				(type solid)
			)
			(fill yes)
			(layer "F.Paste")
		)
		(fp_poly
			(pts
				(xy 3.878 2.726) (xy 3.625 2.726) (xy 3.625 1.226) (xy 3.878 1.226)
			)
			(stroke
				(width 0.01)
				(type solid)
			)
			(fill yes)
			(layer "F.Paste")
		)
		(fp_poly
			(pts
				(xy 4.377 -1.225) (xy 4.124 -1.225) (xy 4.124 -2.725) (xy 4.377 -2.725)
			)
			(stroke
				(width 0.01)
				(type solid)
			)
			(fill yes)
			(layer "F.Paste")
		)
		(fp_poly
			(pts
				(xy 4.377 2.726) (xy 4.124 2.726) (xy 4.124 1.226) (xy 4.377 1.226)
			)
			(stroke
				(width 0.01)
				(type solid)
			)
			(fill yes)
			(layer "F.Paste")
		)
		(fp_poly
			(pts
				(xy 4.877 -1.225) (xy 4.624 -1.225) (xy 4.624 -2.725) (xy 4.877 -2.725)
			)
			(stroke
				(width 0.01)
				(type solid)
			)
			(fill yes)
			(layer "F.Paste")
		)
		(fp_poly
			(pts
				(xy 4.877 2.726) (xy 4.624 2.726) (xy 4.624 1.226) (xy 4.877 1.226)
			)
			(stroke
				(width 0.01)
				(type solid)
			)
			(fill yes)
			(layer "F.Paste")
		)
		(fp_rect
			(start 8.651 2.926)
			(end -8.65 -2.925)
			(stroke
				(width 0.05)
				(type solid)
			)
			(fill no)
			(layer "F.CrtYd")
		)
		(fp_line
			(start -8.39 1.35)
			(end -7.27 2.47)
			(stroke
				(width 0.15)
				(type solid)
			)
			(layer "F.Fab")
		)
		(fp_rect
			(start 8.401 2.476)
			(end -8.4 -2.475)
			(stroke
				(width 0.15)
				(type solid)
			)
			(fill no)
			(layer "F.Fab")
		)
		(pad "" np_thru_hole circle
			(at -6.9 1.401 180)
			(size 1.45 1.45)
			(drill 1.45)
			(layers "*.Cu" "*.Mask")
		)
		(pad "" np_thru_hole circle
			(at 6.901 1.401 180)
			(size 1.45 1.45)
			(drill 1.45)
			(layers "*.Cu" "*.Mask")
		)
		(pad "1" smd rect
			(at -4.748 1.976 270)
			(size 1.5 0.3)
			(layers "F.Cu" "F.Mask")
			(net 1 "GND")
			(pintype "passive")
		)
		(pad "2" smd rect
			(at -4.748 -1.975 270)
			(size 1.5 0.3)
			(layers "F.Cu" "F.Mask")
			(net 1098 "/Supervisior MCU/USB_D1")
			(pintype "passive")
		)
		(pad "3" smd rect
			(at -4.248 1.976 270)
			(size 1.5 0.3)
			(layers "F.Cu" "F.Mask")
			(net 1 "GND")
			(pintype "passive")
		)
		(pad "4" smd rect
			(at -4.248 -1.975 270)
			(size 1.5 0.3)
			(layers "F.Cu" "F.Mask")
			(net 1110 "/Supervisior MCU/USB_D4")
			(pintype "passive")
		)
		(pad "5" smd rect
			(at -3.749 1.976 270)
			(size 1.5 0.3)
			(layers "F.Cu" "F.Mask")
			(net 1099 "/Supervisior MCU/USB_D0")
			(pintype "passive")
		)
		(pad "6" smd rect
			(at -3.749 -1.975 270)
			(size 1.5 0.3)
			(layers "F.Cu" "F.Mask")
			(net 1111 "/Supervisior MCU/USB_D5")
			(pintype "passive")
		)
		(pad "7" smd rect
			(at -3.249 1.976 270)
			(size 1.5 0.3)
			(layers "F.Cu" "F.Mask")
			(net 1109 "/Supervisior MCU/USB_D3")
			(pintype "passive")
		)
		(pad "8" smd rect
			(at -3.249 -1.975 270)
			(size 1.5 0.3)
			(layers "F.Cu" "F.Mask")
			(net 1102 "/Supervisior MCU/SCL0")
			(pintype "passive")
		)
		(pad "9" smd rect
			(at -2.749 1.976 270)
			(size 1.5 0.3)
			(layers "F.Cu" "F.Mask")
			(net 1112 "/Supervisior MCU/USB_D6")
			(pintype "passive")
		)
		(pad "10" smd rect
			(at -2.749 -1.975 270)
			(size 1.5 0.3)
			(layers "F.Cu" "F.Mask")
			(net 1106 "/Supervisior MCU/TEMP_ALERT_N")
			(pintype "passive")
		)
		(pad "11" smd rect
			(at -2.249 1.976 270)
			(size 1.5 0.3)
			(layers "F.Cu" "F.Mask")
			(net 1113 "/Supervisior MCU/USB_D7")
			(pintype "passive")
		)
		(pad "12" smd rect
			(at -2.249 -1.975 270)
			(size 1.5 0.3)
			(layers "F.Cu" "F.Mask")
			(net 1103 "/Supervisior MCU/FPGA_M0")
			(pintype "passive")
		)
		(pad "13" smd rect
			(at -1.749 1.976 270)
			(size 1.5 0.3)
			(layers "F.Cu" "F.Mask")
			(net 1095 "/Supervisior MCU/USB_CE")
			(pintype "passive")
		)
		(pad "14" smd rect
			(at -1.749 -1.975 270)
			(size 1.5 0.3)
			(layers "F.Cu" "F.Mask")
			(net 1116 "/Supervisior MCU/USB_SPARE2")
			(pintype "passive")
		)
		(pad "15" smd rect
			(at -1.249 1.976 270)
			(size 1.5 0.3)
			(layers "F.Cu" "F.Mask")
			(net 1060 "/Supervisior MCU/CFG_INITB")
			(pintype "passive")
		)
		(pad "16" smd rect
			(at -1.249 -1.975 270)
			(size 1.5 0.3)
			(layers "F.Cu" "F.Mask")
			(net 1115 "/Supervisior MCU/USB_SPARE1")
			(pintype "passive")
		)
		(pad "17" smd rect
			(at -0.748 1.976 270)
			(size 1.5 0.3)
			(layers "F.Cu" "F.Mask")
			(net 250 "/Supervisior MCU/CFG_DONE")
			(pintype "passive")
		)
		(pad "18" smd rect
			(at -0.748 -1.975 270)
			(size 1.5 0.3)
			(layers "F.Cu" "F.Mask")
			(net 1104 "/Supervisior MCU/FPGA_M1")
			(pintype "passive")
		)
		(pad "19" smd rect
			(at -0.248 1.976 270)
			(size 1.5 0.3)
			(layers "F.Cu" "F.Mask")
			(net 1054 "/Supervisior MCU/CFG_PROGRAMB")
			(pintype "passive")
		)
		(pad "20" smd rect
			(at -0.248 -1.975 270)
			(size 1.5 0.3)
			(layers "F.Cu" "F.Mask")
			(net 260 "/Supervisior MCU/FPGA_CFG_CS")
			(pintype "passive")
		)
		(pad "21" smd rect
			(at 0.25 1.976 270)
			(size 1.5 0.3)
			(layers "F.Cu" "F.Mask")
			(net 975 "/Supervisior MCU/FPGA_CIPO")
			(pintype "passive")
		)
		(pad "22" smd rect
			(at 0.25 -1.975 270)
			(size 1.5 0.3)
			(layers "F.Cu" "F.Mask")
			(net 1092 "/Supervisior MCU/USB_CLK1_SPARE")
			(pintype "passive")
		)
		(pad "23" smd rect
			(at 0.75 1.976 270)
			(size 1.5 0.3)
			(layers "F.Cu" "F.Mask")
			(net 1114 "/Supervisior MCU/USB_SPARE0")
			(pintype "passive")
		)
		(pad "24" smd rect
			(at 0.75 -1.975 270)
			(size 1.5 0.3)
			(layers "F.Cu" "F.Mask")
			(net 1117 "/Supervisior MCU/USB_SPARE3")
			(pintype "passive")
		)
		(pad "25" smd rect
			(at 1.25 1.976 270)
			(size 1.5 0.3)
			(layers "F.Cu" "F.Mask")
			(net 1088 "/Supervisior MCU/PGOOD_1V2")
			(pintype "passive")
		)
		(pad "26" smd rect
			(at 1.25 -1.975 270)
			(size 1.5 0.3)
			(layers "F.Cu" "F.Mask")
			(net 1085 "/Supervisior MCU/PGOOD_VCCINT")
			(pintype "passive")
		)
		(pad "27" smd rect
			(at 1.75 1.976 270)
			(size 1.5 0.3)
			(layers "F.Cu" "F.Mask")
			(net 1105 "/Supervisior MCU/FPGA_M2")
			(pintype "passive")
		)
		(pad "28" smd rect
			(at 1.75 -1.975 270)
			(size 1.5 0.3)
			(layers "F.Cu" "F.Mask")
			(net 1107 "/Supervisior MCU/USB_C_PD_RST")
			(pintype "passive")
		)
		(pad "29" smd rect
			(at 2.25 1.976 270)
			(size 1.5 0.3)
			(layers "F.Cu" "F.Mask")
			(net 1069 "/Supervisior MCU/USB_A8")
			(pintype "passive")
		)
		(pad "30" smd rect
			(at 2.25 -1.975 270)
			(size 1.5 0.3)
			(layers "F.Cu" "F.Mask")
			(net 955 "/Supervisior MCU/FPGA_COPI")
			(pintype "passive")
		)
		(pad "31" smd rect
			(at 2.75 1.976 270)
			(size 1.5 0.3)
			(layers "F.Cu" "F.Mask")
			(net 1090 "/Supervisior MCU/USB_SPI_COPI")
			(pintype "passive")
		)
		(pad "32" smd rect
			(at 2.75 -1.975 270)
			(size 1.5 0.3)
			(layers "F.Cu" "F.Mask")
			(net 1100 "/Supervisior MCU/USB_WR")
			(pintype "passive")
		)
		(pad "33" smd rect
			(at 3.25 1.976 270)
			(size 1.5 0.3)
			(layers "F.Cu" "F.Mask")
			(net 1091 "/Supervisior MCU/USB_SPI_CIPO")
			(pintype "passive")
		)
		(pad "34" smd rect
			(at 3.25 -1.975 270)
			(size 1.5 0.3)
			(layers "F.Cu" "F.Mask")
			(net 1093 "/Supervisior MCU/USB_ALE")
			(pintype "passive")
		)
		(pad "35" smd rect
			(at 3.75 1.976 270)
			(size 1.5 0.3)
			(layers "F.Cu" "F.Mask")
			(net 1096 "/Supervisior MCU/USB_SPI_CS")
			(pintype "passive")
		)
		(pad "36" smd rect
			(at 3.75 -1.975 270)
			(size 1.5 0.3)
			(layers "F.Cu" "F.Mask")
			(net 1086 "/Supervisior MCU/PGOOD_3V3")
			(pintype "passive")
		)
		(pad "37" smd rect
			(at 4.25 1.976 270)
			(size 1.5 0.3)
			(layers "F.Cu" "F.Mask")
			(net 1089 "/Supervisior MCU/USB_SPI_SCK")
			(pintype "passive")
		)
		(pad "38" smd rect
			(at 4.25 -1.975 270)
			(size 1.5 0.3)
			(layers "F.Cu" "F.Mask")
			(net 1070 "/Supervisior MCU/USB_A9")
			(pintype "passive")
		)
		(pad "39" smd rect
			(at 4.75 1.976 270)
			(size 1.5 0.3)
			(layers "F.Cu" "F.Mask")
			(net 1097 "/Supervisior MCU/USB_D2")
			(pintype "passive")
		)
		(pad "40" smd rect
			(at 4.75 -1.975 270)
			(size 1.5 0.3)
			(layers "F.Cu" "F.Mask")
			(net 1094 "/Supervisior MCU/USB_RD")
			(pintype "passive")
		)
	)
)
